# SCM (Grand Teton) — schematic netlist excerpt (pin names and nets, part order shuffled) for the footprints in the layout excerpt that follows; sources: Cadence DE-HDL packaged netlist, KiCad conversion of 12092022_DA0F0TMDCD0_F0T_Management_Board_D_brd_V3_OCP.brd

R439  Q_RES  33.2 1% CHIP  pkg 0402LF  page 13 : A = FM_PECI_SEL_N ; B = FM_PECI_SEL_R_N
R594  Q_RES  33.2 1% CHIP  pkg 0402LF  page 44 : A = SPI_TPM_CS_N ; B = SPI_TPM_CS_R_N

(kicad_pcb
	(version 20260206)
	(generator "pcbnew")
	(generator_version "10.0")
	(general
		(thickness 1.6)
		(legacy_teardrops no)
	)
	(paper "A4")
	(title_block
		(title "12092022_DA0F0TMDCD0_F0T_Management_Board_D_brd_V3_OCP.brd")
		(comment 1 "Grand Teton / footprints 692-693 of 1440")
	)
	(layers
		(0 "F.Cu" signal "TOP")
		(4 "In1.Cu" signal "GND")
		(6 "In2.Cu" signal "IN1")
		(8 "In3.Cu" signal "GND1")
		(10 "In4.Cu" signal "IN2")
		(12 "In5.Cu" signal "VCC")
		(14 "In6.Cu" signal "VCC1")
		(16 "In7.Cu" signal "IN3")
		(18 "In8.Cu" signal "GND2")
		(20 "In9.Cu" signal "IN4")
		(22 "In10.Cu" signal "GND3")
		(2 "B.Cu" signal "BOTTOM")
		(9 "F.Adhes" user "F.Adhesive")
		(11 "B.Adhes" user "B.Adhesive")
		(13 "F.Paste" user "Package Geometry/Pastemask Top")
		(15 "B.Paste" user "Package Geometry/Pastemask Bottom")
		(5 "F.SilkS" user "Ref Des/Silkscreen Top")
		(7 "B.SilkS" user "Ref Des/Silkscreen Bottom")
		(1 "F.Mask" user "Board Geometry/Soldermask Top")
		(3 "B.Mask" user "Board Geometry/Soldermask Bottom")
		(17 "Dwgs.User" user "User.Drawings")
		(19 "Cmts.User" user "User.Comments")
		(21 "Eco1.User" user "User.Eco1")
		(23 "Eco2.User" user "User.Eco2")
		(25 "Edge.Cuts" user "Board Geometry/Outline")
		(27 "Margin" user)
		(31 "F.CrtYd" user "Package Geometry/Place Bound Top")
		(29 "B.CrtYd" user "Package Geometry/Place Bound Bottom")
		(35 "F.Fab" user "Ref Des/Assembly Top")
		(33 "B.Fab" user "Ref Des/Assembly Bottom")
	)
	(footprint ""
		(layer "F.Cu")
		(at 12.319 -83.312 180)
		(property "Reference" "R439"
			(at 0 0 180)
			(layer "F.SilkS")
			(hide yes)
			(effects
				(font
					(size 1.27 1.27)
				)
			)
		)
		(property "Value" ""
			(at 0 0 180)
			(layer "F.Fab")
			(effects
				(font
					(size 1.27 1.27)
				)
			)
		)
		(duplicate_pad_numbers_are_jumpers no)
		(fp_line
			(start 0.7874 0.4064)
			(end -0.7874 0.4064)
			(stroke
				(width 0.1524)
				(type default)
			)
			(layer "F.SilkS")
		)
		(fp_line
			(start 0.7874 -0.4064)
			(end 0.7874 0.4064)
			(stroke
				(width 0.1524)
				(type default)
			)
			(layer "F.SilkS")
		)
		(fp_line
			(start -0.7874 0.4064)
			(end -0.7874 -0.4064)
			(stroke
				(width 0.1524)
				(type default)
			)
			(layer "F.SilkS")
		)
		(fp_line
			(start -0.7874 -0.4064)
			(end 0.7874 -0.4064)
			(stroke
				(width 0.1524)
				(type default)
			)
			(layer "F.SilkS")
		)
		(fp_line
			(start 0.67945 0.3048)
			(end 0.120396 0.3048)
			(stroke
				(width 0.1)
				(type default)
			)
			(layer "F.Fab")
		)
		(fp_line
			(start 0.67945 -0.3048)
			(end 0.67945 0.3048)
			(stroke
				(width 0.1)
				(type default)
			)
			(layer "F.Fab")
		)
		(fp_line
			(start 0.12065 -0.2794)
			(end 0.12065 -0.3048)
			(stroke
				(width 0.1)
				(type default)
			)
			(layer "F.Fab")
		)
		(fp_line
			(start 0.12065 -0.3048)
			(end 0.67945 -0.3048)
			(stroke
				(width 0.1)
				(type default)
			)
			(layer "F.Fab")
		)
		(fp_line
			(start 0.120396 0.3048)
			(end 0.120396 0.2794)
			(stroke
				(width 0.1)
				(type default)
			)
			(layer "F.Fab")
		)
		(fp_line
			(start 0.120396 0.2794)
			(end -0.12065 0.2794)
			(stroke
				(width 0.1)
				(type default)
			)
			(layer "F.Fab")
		)
		(fp_line
			(start -0.12065 0.3048)
			(end -0.67945 0.3048)
			(stroke
				(width 0.1)
				(type default)
			)
			(layer "F.Fab")
		)
		(fp_line
			(start -0.12065 0.2794)
			(end -0.12065 0.3048)
			(stroke
				(width 0.1)
				(type default)
			)
			(layer "F.Fab")
		)
		(fp_line
			(start -0.12065 -0.2794)
			(end 0.12065 -0.2794)
			(stroke
				(width 0.1)
				(type default)
			)
			(layer "F.Fab")
		)
		(fp_line
			(start -0.12065 -0.305054)
			(end -0.12065 -0.2794)
			(stroke
				(width 0.1)
				(type default)
			)
			(layer "F.Fab")
		)
		(fp_line
			(start -0.67945 0.3048)
			(end -0.67945 -0.305054)
			(stroke
				(width 0.1)
				(type default)
			)
			(layer "F.Fab")
		)
		(fp_line
			(start -0.67945 -0.305054)
			(end -0.12065 -0.305054)
			(stroke
				(width 0.1)
				(type default)
			)
			(layer "F.Fab")
		)
		(pad "1" smd circle
			(at -0.40005 0 180)
			(size 0 0)
			(layers "F.Cu" "F.Mask" "F.Paste")
			(net "FM_PECI_SEL_N")
		)
		(pad "2" smd circle
			(at 0.40005 0 180)
			(size 0 0)
			(layers "F.Cu" "F.Mask" "F.Paste")
			(net "FM_PECI_SEL_R_N")
		)
	)
	(footprint ""
		(layer "F.Cu")
		(at 69.0626 -108.0262 -90)
		(property "Reference" "R594"
			(at 0 0 270)
			(layer "F.SilkS")
			(hide yes)
			(effects
				(font
					(size 1.27 1.27)
				)
			)
		)
		(property "Value" ""
			(at 0 0 270)
			(layer "F.Fab")
			(effects
				(font
					(size 1.27 1.27)
				)
			)
		)
		(duplicate_pad_numbers_are_jumpers no)
		(fp_line
			(start -0.7874 0.4064)
			(end -0.7874 -0.4064)
			(stroke
				(width 0.1524)
				(type default)
			)
			(layer "F.SilkS")
		)
		(fp_line
			(start 0.7874 0.4064)
			(end -0.7874 0.4064)
			(stroke
				(width 0.1524)
				(type default)
			)
			(layer "F.SilkS")
		)
		(fp_line
			(start -0.7874 -0.4064)
			(end 0.7874 -0.4064)
			(stroke
				(width 0.1524)
				(type default)
			)
			(layer "F.SilkS")
		)
		(fp_line
			(start 0.7874 -0.4064)
			(end 0.7874 0.4064)
			(stroke
				(width 0.1524)
				(type default)
			)
			(layer "F.SilkS")
		)
		(fp_line
			(start -0.67945 0.3048)
			(end -0.67945 -0.305054)
			(stroke
				(width 0.1)
				(type default)
			)
			(layer "F.Fab")
		)
		(fp_line
			(start -0.12065 0.3048)
			(end -0.67945 0.3048)
			(stroke
				(width 0.1)
				(type default)
			)
			(layer "F.Fab")
		)
		(fp_line
			(start 0.120396 0.3048)
			(end 0.120396 0.2794)
			(stroke
				(width 0.1)
				(type default)
			)
			(layer "F.Fab")
		)
		(fp_line
			(start 0.67945 0.3048)
			(end 0.120396 0.3048)
			(stroke
				(width 0.1)
				(type default)
			)
			(layer "F.Fab")
		)
		(fp_line
			(start -0.12065 0.2794)
			(end -0.12065 0.3048)
			(stroke
				(width 0.1)
				(type default)
			)
			(layer "F.Fab")
		)
		(fp_line
			(start 0.120396 0.2794)
			(end -0.12065 0.2794)
			(stroke
				(width 0.1)
				(type default)
			)
			(layer "F.Fab")
		)
		(fp_line
			(start -0.12065 -0.2794)
			(end 0.12065 -0.2794)
			(stroke
				(width 0.1)
				(type default)
			)
			(layer "F.Fab")
		)
		(fp_line
			(start 0.12065 -0.2794)
			(end 0.12065 -0.3048)
			(stroke
				(width 0.1)
				(type default)
			)
			(layer "F.Fab")
		)
		(fp_line
			(start 0.12065 -0.3048)
			(end 0.67945 -0.3048)
			(stroke
				(width 0.1)
				(type default)
			)
			(layer "F.Fab")
		)
		(fp_line
			(start 0.67945 -0.3048)
			(end 0.67945 0.3048)
			(stroke
				(width 0.1)
				(type default)
			)
			(layer "F.Fab")
		)
		(fp_line
			(start -0.67945 -0.305054)
			(end -0.12065 -0.305054)
			(stroke
				(width 0.1)
				(type default)
			)
			(layer "F.Fab")
		)
		(fp_line
			(start -0.12065 -0.305054)
			(end -0.12065 -0.2794)
			(stroke
				(width 0.1)
				(type default)
			)
			(layer "F.Fab")
		)
		(pad "1" smd circle
			(at -0.40005 0 270)
			(size 0 0)
			(layers "F.Cu" "F.Mask" "F.Paste")
			(net "SPI_TPM_CS_N")
		)
		(pad "2" smd circle
			(at 0.40005 0 270)
			(size 0 0)
			(layers "F.Cu" "F.Mask" "F.Paste")
			(net "SPI_TPM_CS_R_N")
		)
	)
)
